# T6G (Grand Teton) — schematic netlist excerpt (pin names and nets, part order shuffled) for the footprints in the layout excerpt that follows; sources: Cadence DE-HDL packaged netlist, KiCad conversion of 04192023_DAF0TMB3IC0_F0TG_MB_C_brd_V02_OCP.brd

J68  SCONN288_DDR506112002KQ  IO  pkg DDR288S_1-1VXC  page 95
  VIN_BULK0  = P12V_MEM_CPU0
  RFU0  = NC
  VIN_MGMT  = P3V3_AUX
  HSCL  = I3C_SPD_DDRJ_CPU0_SCL
  HSDA  = I3C_SPD_DDRJ_CPU0_SDA
  VSS0  = GND
  DQ0_A  = M_J_CPU0_SA_DQ<0>
  VSS1  = GND
  DQ1_A  = M_J_CPU0_SA_DQ<1>
  VSS2  = GND
  DQS0_A_T  = M_J_CPU0_SA_DQS_DP<0>
  DQS0_A_C  = M_J_CPU0_SA_DQS_DN<0>
  VSS3  = GND
  DQ4_A  = M_J_CPU0_SA_DQ<4>
  VSS4  = GND
  DQ5_A  = M_J_CPU0_SA_DQ<5>
  VSS5  = GND
  DQ8_A  = M_J_CPU0_SA_DQ<8>
  VSS6  = GND
  DQ9_A  = M_J_CPU0_SA_DQ<9>
  VSS7  = GND
  DQS1_A_T  = M_J_CPU0_SA_DQS_DP<1>
  DQS1_A_C  = M_J_CPU0_SA_DQS_DN<1>
  VSS8  = GND
  DQ12_A  = M_J_CPU0_SA_DQ<12>
  VSS9  = GND
  DQ13_A  = M_J_CPU0_SA_DQ<13>
  VSS10  = GND
  DQ16_A  = M_J_CPU0_SA_DQ<16>
  VSS11  = GND
  DQ17_A  = M_J_CPU0_SA_DQ<17>
  VSS12  = GND
  DQS2_A_T  = M_J_CPU0_SA_DQS_DP<2>
  DQS2_A_C  = M_J_CPU0_SA_DQS_DN<2>
  VSS13  = GND
  DQ20_A  = M_J_CPU0_SA_DQ<20>
  VSS14  = GND
  DQ21_A  = M_J_CPU0_SA_DQ<21>
  VSS15  = GND
  DQ24_A  = M_J_CPU0_SA_DQ<24>
  VSS16  = GND
  DQ25_A  = M_J_CPU0_SA_DQ<25>
  VSS17  = GND
  DQS3_A_T  = M_J_CPU0_SA_DQS_DP<3>
  DQS3_A_C  = M_J_CPU0_SA_DQS_DN<3>
  VSS18  = GND
  DQ28_A  = M_J_CPU0_SA_DQ<28>
  VSS19  = GND
  DQ29_A  = M_J_CPU0_SA_DQ<29>
  VSS20  = GND
  CB0_A  = M_J_CPU0_SA_CB<0>
  VSS21  = GND
  CB1_A  = M_J_CPU0_SA_CB<1>
  VSS22  = GND
  DQS4_A_T  = M_J_CPU0_SA_DQS_DP<4>
  DQS4_A_C  = M_J_CPU0_SA_DQS_DN<4>
  VSS23  = GND
  CB4_A  = M_J_CPU0_SA_CB<4>
  VSS24  = GND
  CB5_A  = M_J_CPU0_SA_CB<5>
  VSS25  = GND
  ALERT_N  = M_J_CPU0_ALERT_N
  VSS26  = GND
  CS0_A_N  = M_J_CPU0_SA_CS_N<0>
  VSS27  = GND
  CA0_A  = M_J_CPU0_SA_CA<0>
  VSS28  = GND
  CA2_A  = M_J_CPU0_SA_CA<2>
  VSS29  = GND
  CA4_A  = M_J_CPU0_SA_CA<4>
  VSS30  = GND
  CA6_A  = M_J_CPU0_SA_CA<6>
  VSS31  = GND
  PAR_A  = M_J_CPU0_SA_PAR
  VSS32  = GND
  CA0_B  = M_J_CPU0_SB_CA<0>
  VSS33  = GND
  CA2_B  = M_J_CPU0_SB_CA<2>
  VSS34  = GND
  CA4_B  = M_J_CPU0_SB_CA<4>
  VSS35  = GND
  CA6_B  = M_J_CPU0_SB_CA<6>
  VSS36  = GND
  CS0_B_N  = M_J_CPU0_SB_CS_N<0>
  VSS37  = GND
  \lbd||rsp_a_n\  = M_J_CPU0_SA_RSP<0>
  \lbs||rsp_b_n\  = M_J_CPU0_SB_RSP<0>
  VSS38  = GND
  CB4_B  = M_J_CPU0_SB_CB<4>
  VSS39  = GND
  CB5_B  = M_J_CPU0_SB_CB<5>
  VSS40  = GND
  \dqs9_b_t||tdqs9_b_t||dbi4_b_n\  = M_J_CPU0_SB_DQS_DP<9>
  \dqs9_b_c||tdqs9_b_c\  = M_J_CPU0_SB_DQS_DN<9>
  VSS41  = GND
  CB0_B  = M_J_CPU0_SB_CB<0>
  VSS42  = GND
  CB1_B  = M_J_CPU0_SB_CB<1>
  VSS43  = GND
  DQ0_B  = M_J_CPU0_SB_DQ<0>
  VSS44  = GND
  DQ1_B  = M_J_CPU0_SB_DQ<1>
  VSS45  = GND
  DQS0_B_T  = M_J_CPU0_SB_DQS_DP<0>
  DQS0_B_C  = M_J_CPU0_SB_DQS_DN<0>
  VSS46  = GND
  DQ4_B  = M_J_CPU0_SB_DQ<4>
  VSS47  = GND
  DQ5_B  = M_J_CPU0_SB_DQ<5>
  VSS48  = GND
  DQ8_B  = M_J_CPU0_SB_DQ<8>
  VSS49  = GND
  DQ9_B  = M_J_CPU0_SB_DQ<9>
  VSS50  = GND
  DQS1_B_T  = M_J_CPU0_SB_DQS_DP<1>
  DQS1_B_C  = M_J_CPU0_SB_DQS_DN<1>
  VSS51  = GND
  DQ12_B  = M_J_CPU0_SB_DQ<12>
  VSS52  = GND
  DQ13_B  = M_J_CPU0_SB_DQ<13>
  VSS53  = GND
  DQ16_B  = M_J_CPU0_SB_DQ<16>
  VSS54  = GND
  DQ17_B  = M_J_CPU0_SB_DQ<17>
  VSS55  = GND
  DQS2_B_T  = M_J_CPU0_SB_DQS_DP<2>
  DQS2_B_C  = M_J_CPU0_SB_DQS_DN<2>
  VSS56  = GND
  DQ20_B  = M_J_CPU0_SB_DQ<20>
  VSS57  = GND
  DQ21_B  = M_J_CPU0_SB_DQ<21>
  VSS58  = GND
  DQ24_B  = M_J_CPU0_SB_DQ<24>
  VSS59  = GND
  DQ25_B  = M_J_CPU0_SB_DQ<25>
  VSS60  = GND
  DQS3_B_T  = M_J_CPU0_SB_DQS_DP<3>
  DQS3_B_C  = M_J_CPU0_SB_DQS_DN<3>
  VSS61  = GND
  DQ28_B  = M_J_CPU0_SB_DQ<28>
  VSS62  = GND
  DQ29_B  = M_J_CPU0_SB_DQ<29>
  VSS63  = GND
  RFU1  = NC
  VIN_BULK1  = P12V_MEM_CPU0
  VIN_BULK2  = P12V_MEM_CPU0
  \pwr_good||fail_n\  = PWRGD_CHJ_CPU0_DIMM
  HAS  = PD_CHJ_CPU0_DIMM_SAA
  RFU2  = NC
  RFU3  = NC
  VSS64  = GND
  DQ2_A  = M_J_CPU0_SA_DQ<2>
  VSS65  = GND
  DQ3_A  = M_J_CPU0_SA_DQ<3>
  VSS66  = GND
  \dqs5_a_c||tdqs5_a_c||dqs5_a_t||tdqs5_a_t\  = M_J_CPU0_SA_DQS_DN<5>
  \dqs5_a_t||tdqs5_a_t\  = M_J_CPU0_SA_DQS_DP<5>
  VSS67  = GND
  DQ6_A  = M_J_CPU0_SA_DQ<6>
  VSS68  = GND
  DQ7_A  = M_J_CPU0_SA_DQ<7>
  VSS69  = GND
  DQ10_A  = M_J_CPU0_SA_DQ<10>
  VSS70  = GND
  DQ11_A  = M_J_CPU0_SA_DQ<11>
  VSS71  = GND
  \dqs6_a_c||tdqs6_a_c||dqs6_a_t||tdqs6_a_t\  = M_J_CPU0_SA_DQS_DN<6>
  \dqs6_a_t||tdqs6_a_t\  = M_J_CPU0_SA_DQS_DP<6>
  VSS72  = GND
  DQ14_A  = M_J_CPU0_SA_DQ<14>
  VSS73  = GND
  DQ15_A  = M_J_CPU0_SA_DQ<15>
  VSS74  = GND
  DQ18_A  = M_J_CPU0_SA_DQ<18>
  VSS75  = GND
  DQ19_A  = M_J_CPU0_SA_DQ<19>
  VSS76  = GND
  \dqs7_a_c||tdqs7_a_c\  = M_J_CPU0_SA_DQS_DN<7>
  \dqs7_a_t||tdqs7_a_t\  = M_J_CPU0_SA_DQS_DP<7>
  VSS77  = GND
  DQ22_A  = M_J_CPU0_SA_DQ<22>
  VSS78  = GND
  DQ23_A  = M_J_CPU0_SA_DQ<23>
  VSS79  = GND
  DQ26_A  = M_J_CPU0_SA_DQ<26>
  VSS80  = GND
  DQ27_A  = M_J_CPU0_SA_DQ<27>
  VSS81  = GND
  \dqs8_a_c||tdqs8_a_c\  = M_J_CPU0_SA_DQS_DN<8>
  \dqs8_a_t||tdqs8_a_t\  = M_J_CPU0_SA_DQS_DP<8>
  VSS82  = GND
  DQ30_A  = M_J_CPU0_SA_DQ<30>
  VSS83  = GND
  DQ31_A  = M_J_CPU0_SA_DQ<31>
  VSS84  = GND
  CB2_A  = M_J_CPU0_SA_CB<2>
  VSS85  = GND
  CB3_A  = M_J_CPU0_SA_CB<3>
  VSS86  = GND
  \dqs9_a_c||tdqs9_a_c\  = M_J_CPU0_SA_DQS_DN<9>
  \dqs9_a_t||tdqs9_a_t\  = M_J_CPU0_SA_DQS_DP<9>
  VSS87  = GND
  CB6_A  = M_J_CPU0_SA_CB<6>
  VSS88  = GND
  CB7_A  = M_J_CPU0_SA_CB<7>
  VSS89  = GND
  RESET_N  = M_J_CPU0_RESET_N
  VSS90  = GND
  CS1_A_N  = M_J_CPU0_SA_CS_N<1>
  VSS91  = GND
  CA1_A  = M_J_CPU0_SA_CA<1>
  VSS92  = GND
  CA3_A  = M_J_CPU0_SA_CA<3>
  VSS93  = GND
  CA5_A  = M_J_CPU0_SA_CA<5>
  VSS94  = GND
  CK_T  = M_J_CPU0_CLK_DP<0>
  CK_C  = M_J_CPU0_CLK_DN<0>
  VSS95  = GND
  RFU4  = NC
  CA1_B  = M_J_CPU0_SB_CA<1>
  VSS96  = GND
  CA3_B  = M_J_CPU0_SB_CA<3>
  VSS97  = GND
  CA5_B  = M_J_CPU0_SB_CA<5>
  VSS98  = GND
  PAR_B  = M_J_CPU0_SB_PAR
  VSS99  = GND
  CS1_B_N  = M_J_CPU0_SB_CS_N<1>
  VSS100  = GND
  RFU5  = NC
  RFU6  = NC
  VSS101  = GND
  CB6_B  = M_J_CPU0_SB_CB<6>
  VSS102  = GND
  CB7_B  = M_J_CPU0_SB_CB<7>
  VSS103  = GND
  DQS4_B_C  = M_J_CPU0_SB_DQS_DN<4>
  DQS4_B_T  = M_J_CPU0_SB_DQS_DP<4>
  VSS104  = GND
  CB2_B  = M_J_CPU0_SB_CB<2>
  VSS105  = GND
  CB3_B  = M_J_CPU0_SB_CB<3>
  VSS106  = GND
  DQ2_B  = M_J_CPU0_SB_DQ<2>
  VSS107  = GND
  DQ3_B  = M_J_CPU0_SB_DQ<3>
  VSS108  = GND
  \dqs5_b_c||tdqs5_b_c\  = M_J_CPU0_SB_DQS_DN<5>
  \dqs5_b_t||tdqs5_b_t\  = M_J_CPU0_SB_DQS_DP<5>
  VSS109  = GND
  DQ6_B  = M_J_CPU0_SB_DQ<6>
  VSS110  = GND
  DQ7_B  = M_J_CPU0_SB_DQ<7>
  VSS111  = GND
  DQ10_B  = M_J_CPU0_SB_DQ<10>
  VSS112  = GND
  DQ11_B  = M_J_CPU0_SB_DQ<11>
  VSS113  = GND
  \dqs6_b_c||tdqs6_b_c\  = M_J_CPU0_SB_DQS_DN<6>
  \dqs6_b_t||tdqs6_b_t\  = M_J_CPU0_SB_DQS_DP<6>
  VSS114  = GND
  DQ14_B  = M_J_CPU0_SB_DQ<14>
  VSS115  = GND
  DQ15_B  = M_J_CPU0_SB_DQ<15>
  VSS116  = GND
  DQ18_B  = M_J_CPU0_SB_DQ<18>
  VSS117  = GND
  DQ19_B  = M_J_CPU0_SB_DQ<19>
  VSS118  = GND
  \dqs7_b_c||tdqs7_b_c\  = M_J_CPU0_SB_DQS_DN<7>
  \dqs7_b_t||tdqs7_b_t\  = M_J_CPU0_SB_DQS_DP<7>
  VSS119  = GND
  DQ22_B  = M_J_CPU0_SB_DQ<22>
  VSS120  = GND
  DQ23_B  = M_J_CPU0_SB_DQ<23>
  VSS121  = GND
  DQ26_B  = M_J_CPU0_SB_DQ<26>
  VSS122  = GND
  DQ27_B  = M_J_CPU0_SB_DQ<27>
  VSS123  = GND
  \dqs8_b_c||tdqs8_b_c\  = M_J_CPU0_SB_DQS_DN<8>
  \dqs8_b_t||tdqs8_b_t\  = M_J_CPU0_SB_DQS_DP<8>
  VSS124  = GND
  DQ30_B  = M_J_CPU0_SB_DQ<30>
  VSS125  = GND
  DQ31_B  = M_J_CPU0_SB_DQ<31>
  VSS126  = GND
  G1  = GND
  G2  = GND
  G3  = GND

(kicad_pcb
	(version 20260206)
	(generator "pcbnew")
	(generator_version "10.0")
	(general
		(thickness 1.6)
		(legacy_teardrops no)
	)
	(paper "A4")
	(title_block
		(title "04192023_DAF0TMB3IC0_F0TG_MB_C_brd_V02_OCP.brd")
		(comment 1 "Grand Teton / footprint 802 of 8354 (J68), pads 46-91 of 291")
	)
	(layers
		(0 "F.Cu" signal "TOP")
		(4 "In1.Cu" signal "GND")
		(6 "In2.Cu" signal "IN1")
		(8 "In3.Cu" signal "GND1")
		(10 "In4.Cu" signal "IN2")
		(12 "In5.Cu" signal "GND2")
		(14 "In6.Cu" signal "IN3")
		(16 "In7.Cu" signal "GND3")
		(18 "In8.Cu" signal "VCC")
		(20 "In9.Cu" signal "VCC1")
		(22 "In10.Cu" signal "GND4")
		(24 "In11.Cu" signal "IN4")
		(26 "In12.Cu" signal "GND5")
		(28 "In13.Cu" signal "IN5")
		(30 "In14.Cu" signal "GND6")
		(32 "In15.Cu" signal "IN6")
		(34 "In16.Cu" signal "GND7")
		(2 "B.Cu" signal "BOTTOM")
		(9 "F.Adhes" user "F.Adhesive")
		(11 "B.Adhes" user "B.Adhesive")
		(13 "F.Paste" user "Package Geometry/Pastemask Top")
		(15 "B.Paste" user "Package Geometry/Pastemask Bottom")
		(5 "F.SilkS" user "Ref Des/Silkscreen Top")
		(7 "B.SilkS" user "Ref Des/Silkscreen Bottom")
		(1 "F.Mask" user "Board Geometry/Soldermask Top")
		(3 "B.Mask" user "Board Geometry/Soldermask Bottom")
		(17 "Dwgs.User" user "User.Drawings")
		(19 "Cmts.User" user "User.Comments")
		(21 "Eco1.User" user "User.Eco1")
		(23 "Eco2.User" user "User.Eco2")
		(25 "Edge.Cuts" user "Board Geometry/Outline")
		(27 "Margin" user)
		(31 "F.CrtYd" user "Package Geometry/Place Bound Top")
		(29 "B.CrtYd" user "Package Geometry/Place Bound Bottom")
		(35 "F.Fab" user "Ref Des/Assembly Top")
		(33 "B.Fab" user "Ref Des/Assembly Bottom")
	)
	(footprint ""
		(layer "F.Cu")
		(at 437.05018 -255.560068 180)
		(property "Reference" "J68"
			(at 1.32334 -81.844388 0)
			(unlocked yes)
			(layer "F.SilkS")
			(effects
				(font
					(size 0.7874 0.5842)
					(thickness 0.1524)
				)
			)
		)
		(property "Value" ""
			(at 0 0 180)
			(layer "F.Fab")
			(effects
				(font
					(size 1.27 1.27)
				)
			)
		)
		(duplicate_pad_numbers_are_jumpers no)
		(pad "46" smd rect
			(at -2.050034 -25.07488 90)
			(size 0.519938 1.4986)
			(layers "F.Cu" "F.Mask" "F.Paste")
			(net "GND")
		)
		(pad "47" smd rect
			(at -2.050034 -24.224996 90)
			(size 0.519938 1.4986)
			(layers "F.Cu" "F.Mask" "F.Paste")
			(net "M_J_CPU0_SA_DQ<28>")
		)
		(pad "48" smd rect
			(at -2.050034 -23.375112 90)
			(size 0.519938 1.4986)
			(layers "F.Cu" "F.Mask" "F.Paste")
			(net "GND")
		)
		(pad "49" smd rect
			(at -2.050034 -22.524974 90)
			(size 0.519938 1.4986)
			(layers "F.Cu" "F.Mask" "F.Paste")
			(net "M_J_CPU0_SA_DQ<29>")
		)
		(pad "50" smd rect
			(at -2.050034 -21.67509 90)
			(size 0.519938 1.4986)
			(layers "F.Cu" "F.Mask" "F.Paste")
			(net "GND")
		)
		(pad "51" smd rect
			(at -2.050034 -20.824952 90)
			(size 0.519938 1.4986)
			(layers "F.Cu" "F.Mask" "F.Paste")
			(net "M_J_CPU0_SA_CB<0>")
		)
		(pad "52" smd rect
			(at -2.050034 -19.975068 90)
			(size 0.519938 1.4986)
			(layers "F.Cu" "F.Mask" "F.Paste")
			(net "GND")
		)
		(pad "53" smd rect
			(at -2.050034 -19.12493 90)
			(size 0.519938 1.4986)
			(layers "F.Cu" "F.Mask" "F.Paste")
			(net "M_J_CPU0_SA_CB<1>")
		)
		(pad "54" smd rect
			(at -2.050034 -18.275046 90)
			(size 0.519938 1.4986)
			(layers "F.Cu" "F.Mask" "F.Paste")
			(net "GND")
		)
		(pad "55" smd rect
			(at -2.050034 -17.424908 90)
			(size 0.519938 1.4986)
			(layers "F.Cu" "F.Mask" "F.Paste")
			(net "M_J_CPU0_SA_DQS_DP<4>")
		)
		(pad "56" smd rect
			(at -2.050034 -16.575024 90)
			(size 0.519938 1.4986)
			(layers "F.Cu" "F.Mask" "F.Paste")
			(net "M_J_CPU0_SA_DQS_DN<4>")
		)
		(pad "57" smd rect
			(at -2.050034 -15.724886 90)
			(size 0.519938 1.4986)
			(layers "F.Cu" "F.Mask" "F.Paste")
			(net "GND")
		)
		(pad "58" smd rect
			(at -2.050034 -14.875002 90)
			(size 0.519938 1.4986)
			(layers "F.Cu" "F.Mask" "F.Paste")
			(net "M_J_CPU0_SA_CB<4>")
		)
		(pad "59" smd rect
			(at -2.050034 -14.025118 90)
			(size 0.519938 1.4986)
			(layers "F.Cu" "F.Mask" "F.Paste")
			(net "GND")
		)
		(pad "60" smd rect
			(at -2.050034 -13.17498 90)
			(size 0.519938 1.4986)
			(layers "F.Cu" "F.Mask" "F.Paste")
			(net "M_J_CPU0_SA_CB<5>")
		)
		(pad "61" smd rect
			(at -2.050034 -12.325096 90)
			(size 0.519938 1.4986)
			(layers "F.Cu" "F.Mask" "F.Paste")
			(net "GND")
		)
		(pad "62" smd rect
			(at -2.050034 -11.474958 90)
			(size 0.519938 1.4986)
			(layers "F.Cu" "F.Mask" "F.Paste")
			(net "M_J_CPU0_ALERT_N")
		)
		(pad "63" smd rect
			(at -2.050034 -10.625074 90)
			(size 0.519938 1.4986)
			(layers "F.Cu" "F.Mask" "F.Paste")
			(net "GND")
		)
		(pad "64" smd rect
			(at -2.050034 -9.774936 90)
			(size 0.519938 1.4986)
			(layers "F.Cu" "F.Mask" "F.Paste")
			(net "M_J_CPU0_SA_CS_N<0>")
		)
		(pad "65" smd rect
			(at -2.050034 -8.925052 90)
			(size 0.519938 1.4986)
			(layers "F.Cu" "F.Mask" "F.Paste")
			(net "GND")
		)
		(pad "66" smd rect
			(at -2.050034 -8.074914 90)
			(size 0.519938 1.4986)
			(layers "F.Cu" "F.Mask" "F.Paste")
			(net "M_J_CPU0_SA_CA<0>")
		)
		(pad "67" smd rect
			(at -2.050034 -7.22503 90)
			(size 0.519938 1.4986)
			(layers "F.Cu" "F.Mask" "F.Paste")
			(net "GND")
		)
		(pad "68" smd rect
			(at -2.050034 -6.374892 90)
			(size 0.519938 1.4986)
			(layers "F.Cu" "F.Mask" "F.Paste")
			(net "M_J_CPU0_SA_CA<2>")
		)
		(pad "69" smd rect
			(at -2.050034 -5.525008 90)
			(size 0.519938 1.4986)
			(layers "F.Cu" "F.Mask" "F.Paste")
			(net "GND")
		)
		(pad "70" smd rect
			(at -2.050034 -4.675124 90)
			(size 0.519938 1.4986)
			(layers "F.Cu" "F.Mask" "F.Paste")
			(net "M_J_CPU0_SA_CA<4>")
		)
		(pad "71" smd rect
			(at -2.050034 -3.824986 90)
			(size 0.519938 1.4986)
			(layers "F.Cu" "F.Mask" "F.Paste")
			(net "GND")
		)
		(pad "72" smd rect
			(at -2.050034 -2.975102 90)
			(size 0.519938 1.4986)
			(layers "F.Cu" "F.Mask" "F.Paste")
			(net "M_J_CPU0_SA_CA<6>")
		)
		(pad "73" smd rect
			(at -2.050034 -2.124964 90)
			(size 0.519938 1.4986)
			(layers "F.Cu" "F.Mask" "F.Paste")
			(net "GND")
		)
		(pad "74" smd rect
			(at -2.050034 -1.27508 90)
			(size 0.519938 1.4986)
			(layers "F.Cu" "F.Mask" "F.Paste")
			(net "M_J_CPU0_SA_PAR")
		)
		(pad "75" smd rect
			(at -2.050034 -0.424942 90)
			(size 0.519938 1.4986)
			(layers "F.Cu" "F.Mask" "F.Paste")
			(net "GND")
		)
		(pad "76" smd rect
			(at -2.050034 5.525008 90)
			(size 0.519938 1.4986)
			(layers "F.Cu" "F.Mask" "F.Paste")
			(net "M_J_CPU0_SB_CA<0>")
		)
		(pad "77" smd rect
			(at -2.050034 6.374892 90)
			(size 0.519938 1.4986)
			(layers "F.Cu" "F.Mask" "F.Paste")
			(net "GND")
		)
		(pad "78" smd rect
			(at -2.050034 7.22503 90)
			(size 0.519938 1.4986)
			(layers "F.Cu" "F.Mask" "F.Paste")
			(net "M_J_CPU0_SB_CA<2>")
		)
		(pad "79" smd rect
			(at -2.050034 8.074914 90)
			(size 0.519938 1.4986)
			(layers "F.Cu" "F.Mask" "F.Paste")
			(net "GND")
		)
		(pad "80" smd rect
			(at -2.050034 8.925052 90)
			(size 0.519938 1.4986)
			(layers "F.Cu" "F.Mask" "F.Paste")
			(net "M_J_CPU0_SB_CA<4>")
		)
		(pad "81" smd rect
			(at -2.050034 9.774936 90)
			(size 0.519938 1.4986)
			(layers "F.Cu" "F.Mask" "F.Paste")
			(net "GND")
		)
		(pad "82" smd rect
			(at -2.050034 10.625074 90)
			(size 0.519938 1.4986)
			(layers "F.Cu" "F.Mask" "F.Paste")
			(net "M_J_CPU0_SB_CA<6>")
		)
		(pad "83" smd rect
			(at -2.050034 11.474958 90)
			(size 0.519938 1.4986)
			(layers "F.Cu" "F.Mask" "F.Paste")
			(net "GND")
		)
		(pad "84" smd rect
			(at -2.050034 12.325096 90)
			(size 0.519938 1.4986)
			(layers "F.Cu" "F.Mask" "F.Paste")
			(net "M_J_CPU0_SB_CS_N<0>")
		)
		(pad "85" smd rect
			(at -2.050034 13.17498 90)
			(size 0.519938 1.4986)
			(layers "F.Cu" "F.Mask" "F.Paste")
			(net "GND")
		)
		(pad "86" smd rect
			(at -2.050034 14.025118 90)
			(size 0.519938 1.4986)
			(layers "F.Cu" "F.Mask" "F.Paste")
			(net "M_J_CPU0_SA_RSP<0>")
		)
		(pad "87" smd rect
			(at -2.050034 14.875002 90)
			(size 0.519938 1.4986)
			(layers "F.Cu" "F.Mask" "F.Paste")
			(net "M_J_CPU0_SB_RSP<0>")
		)
		(pad "88" smd rect
			(at -2.050034 15.724886 90)
			(size 0.519938 1.4986)
			(layers "F.Cu" "F.Mask" "F.Paste")
			(net "GND")
		)
		(pad "89" smd rect
			(at -2.050034 16.575024 90)
			(size 0.519938 1.4986)
			(layers "F.Cu" "F.Mask" "F.Paste")
			(net "M_J_CPU0_SB_CB<4>")
		)
		(pad "90" smd rect
			(at -2.050034 17.424908 90)
			(size 0.519938 1.4986)
			(layers "F.Cu" "F.Mask" "F.Paste")
			(net "GND")
		)
		(pad "91" smd rect
			(at -2.050034 18.275046 90)
			(size 0.519938 1.4986)
			(layers "F.Cu" "F.Mask" "F.Paste")
			(net "M_J_CPU0_SB_CB<5>")
		)
	)
)
